(kicad_pcb
	(version 20260206)
	(generator "pcbnew")
	(generator_version "10.0")
	(general
		(thickness 1.6)
		(legacy_teardrops no)
	)
	(paper "A4")
	(title_block
		(title "Wiwynn_Tioga_Pass_MB.brd")
		(comment 1 "Tioga Pass / footprint 431 of 4770 (J4A1), pads 124-243 of 291")
	)
	(layers
		(0 "F.Cu" signal "TOP")
		(4 "In1.Cu" signal "L2GND")
		(6 "In2.Cu" signal "L3")
		(8 "In3.Cu" signal "L4GND")
		(10 "In4.Cu" signal "L5")
		(12 "In5.Cu" signal "L6GND")
		(14 "In6.Cu" signal "L7VCC")
		(16 "In7.Cu" signal "L8VCC")
		(18 "In8.Cu" signal "L9GND")
		(20 "In9.Cu" signal "L10")
		(22 "In10.Cu" signal "L11GND")
		(24 "In11.Cu" signal "L12")
		(26 "In12.Cu" signal "L13GND")
		(2 "B.Cu" signal "BOTTOM")
		(9 "F.Adhes" user "F.Adhesive")
		(11 "B.Adhes" user "B.Adhesive")
		(13 "F.Paste" user "Package Geometry/Pastemask Top")
		(15 "B.Paste" user "Package Geometry/Pastemask Bottom")
		(5 "F.SilkS" user "Ref Des/Silkscreen Top")
		(7 "B.SilkS" user "Ref Des/Silkscreen Bottom")
		(1 "F.Mask" user "Board Geometry/Soldermask Top")
		(3 "B.Mask" user "Board Geometry/Soldermask Bottom")
		(17 "Dwgs.User" user "User.Drawings")
		(19 "Cmts.User" user "User.Comments")
		(21 "Eco1.User" user "User.Eco1")
		(23 "Eco2.User" user "User.Eco2")
		(25 "Edge.Cuts" user "Board Geometry/Outline")
		(27 "Margin" user)
		(31 "F.CrtYd" user "Package Geometry/Place Bound Top")
		(29 "B.CrtYd" user "Package Geometry/Place Bound Bottom")
		(35 "F.Fab" user "Ref Des/Assembly Top")
		(33 "B.Fab" user "Ref Des/Assembly Bottom")
	)
	(footprint ""
		(layer "F.Cu")
		(at 194.700398 -152.273 90)
		(property "Reference" "J4A1"
			(at -2.699512 42.53611 0)
			(unlocked yes)
			(layer "F.SilkS")
			(effects
				(font
					(size 0.7874 0.5842)
					(thickness 0.1524)
				)
				(justify left)
			)
		)
		(property "Value" ""
			(at 0 0 90)
			(layer "F.Fab")
			(effects
				(font
					(size 1.27 1.27)
				)
			)
		)
		(duplicate_pad_numbers_are_jumpers no)
		(pad "121" smd rect
			(at 0 107.100116 90)
			(size 1.8034 0.508)
			(layers "F.Cu" "F.Mask" "F.Paste")
			(net "M_F_DQS_DP<15>")
		)
		(pad "122" smd rect
			(at 0 107.95 90)
			(size 1.8034 0.508)
			(layers "F.Cu" "F.Mask" "F.Paste")
			(net "M_F_DQS_DN<15>")
		)
		(pad "123" smd rect
			(at 0 108.799884 90)
			(size 1.8034 0.508)
			(layers "F.Cu" "F.Mask" "F.Paste")
			(net "GND")
		)
		(pad "124" smd rect
			(at 0 109.650022 90)
			(size 1.8034 0.508)
			(layers "F.Cu" "F.Mask" "F.Paste")
			(net "M_F_DQ<55>")
		)
		(pad "125" smd rect
			(at 0 110.499906 90)
			(size 1.8034 0.508)
			(layers "F.Cu" "F.Mask" "F.Paste")
			(net "GND")
		)
		(pad "126" smd rect
			(at 0 111.350044 90)
			(size 1.8034 0.508)
			(layers "F.Cu" "F.Mask" "F.Paste")
			(net "M_F_DQ<51>")
		)
		(pad "127" smd rect
			(at 0 112.199928 90)
			(size 1.8034 0.508)
			(layers "F.Cu" "F.Mask" "F.Paste")
			(net "GND")
		)
		(pad "128" smd rect
			(at 0 113.050066 90)
			(size 1.8034 0.508)
			(layers "F.Cu" "F.Mask" "F.Paste")
			(net "M_F_DQ<61>")
		)
		(pad "129" smd rect
			(at 0 113.89995 90)
			(size 1.8034 0.508)
			(layers "F.Cu" "F.Mask" "F.Paste")
			(net "GND")
		)
		(pad "130" smd rect
			(at 0 114.750088 90)
			(size 1.8034 0.508)
			(layers "F.Cu" "F.Mask" "F.Paste")
			(net "M_F_DQ<57>")
		)
		(pad "131" smd rect
			(at 0 115.599972 90)
			(size 1.8034 0.508)
			(layers "F.Cu" "F.Mask" "F.Paste")
			(net "GND")
		)
		(pad "132" smd rect
			(at 0 116.45011 90)
			(size 1.8034 0.508)
			(layers "F.Cu" "F.Mask" "F.Paste")
			(net "M_F_DQS_DP<16>")
		)
		(pad "133" smd rect
			(at 0 117.299994 90)
			(size 1.8034 0.508)
			(layers "F.Cu" "F.Mask" "F.Paste")
			(net "M_F_DQS_DN<16>")
		)
		(pad "134" smd rect
			(at 0 118.149878 90)
			(size 1.8034 0.508)
			(layers "F.Cu" "F.Mask" "F.Paste")
			(net "GND")
		)
		(pad "135" smd rect
			(at 0 119.000016 90)
			(size 1.8034 0.508)
			(layers "F.Cu" "F.Mask" "F.Paste")
			(net "M_F_DQ<63>")
		)
		(pad "136" smd rect
			(at 0 119.8499 90)
			(size 1.8034 0.508)
			(layers "F.Cu" "F.Mask" "F.Paste")
			(net "GND")
		)
		(pad "137" smd rect
			(at 0 120.700038 90)
			(size 1.8034 0.508)
			(layers "F.Cu" "F.Mask" "F.Paste")
			(net "M_F_DQ<59>")
		)
		(pad "138" smd rect
			(at 0 121.549922 90)
			(size 1.8034 0.508)
			(layers "F.Cu" "F.Mask" "F.Paste")
			(net "GND")
		)
		(pad "139" smd rect
			(at 0 122.40006 90)
			(size 1.8034 0.508)
			(layers "F.Cu" "F.Mask" "F.Paste")
			(net "GND")
		)
		(pad "140" smd rect
			(at 0 123.249944 90)
			(size 1.8034 0.508)
			(layers "F.Cu" "F.Mask" "F.Paste")
			(net "GND")
		)
		(pad "141" smd rect
			(at 0 124.100082 90)
			(size 1.8034 0.508)
			(layers "F.Cu" "F.Mask" "F.Paste")
			(net "SMB_DDR_DEF_VPP_SCL")
		)
		(pad "142" smd rect
			(at 0 124.949966 90)
			(size 1.8034 0.508)
			(layers "F.Cu" "F.Mask" "F.Paste")
			(net "PVPP_DEF")
		)
		(pad "143" smd rect
			(at 0 125.800104 90)
			(size 1.8034 0.508)
			(layers "F.Cu" "F.Mask" "F.Paste")
			(net "PVPP_DEF")
		)
		(pad "144" smd rect
			(at 0 126.649988 90)
			(size 1.8034 0.508)
			(layers "F.Cu" "F.Mask" "F.Paste")
			(net "TP_CH_F_DIMM_F0_RFU_2")
		)
		(pad "145" smd rect
			(at 4.59994 0 90)
			(size 1.8034 0.508)
			(layers "F.Cu" "F.Mask" "F.Paste")
			(net "P12V_NVDIMM_DEF")
		)
		(pad "146" smd rect
			(at 4.59994 0.849884 90)
			(size 1.8034 0.508)
			(layers "F.Cu" "F.Mask" "F.Paste")
			(net "M_F_VREF")
		)
		(pad "147" smd rect
			(at 4.59994 1.700022 90)
			(size 1.8034 0.508)
			(layers "F.Cu" "F.Mask" "F.Paste")
			(net "GND")
		)
		(pad "148" smd rect
			(at 4.59994 2.549906 90)
			(size 1.8034 0.508)
			(layers "F.Cu" "F.Mask" "F.Paste")
			(net "M_F_DQ<4>")
		)
		(pad "149" smd rect
			(at 4.59994 3.400044 90)
			(size 1.8034 0.508)
			(layers "F.Cu" "F.Mask" "F.Paste")
			(net "GND")
		)
		(pad "150" smd rect
			(at 4.59994 4.249928 90)
			(size 1.8034 0.508)
			(layers "F.Cu" "F.Mask" "F.Paste")
			(net "M_F_DQ<0>")
		)
		(pad "151" smd rect
			(at 4.59994 5.100066 90)
			(size 1.8034 0.508)
			(layers "F.Cu" "F.Mask" "F.Paste")
			(net "GND")
		)
		(pad "152" smd rect
			(at 4.59994 5.94995 90)
			(size 1.8034 0.508)
			(layers "F.Cu" "F.Mask" "F.Paste")
			(net "M_F_DQS_DN<0>")
		)
		(pad "153" smd rect
			(at 4.59994 6.800088 90)
			(size 1.8034 0.508)
			(layers "F.Cu" "F.Mask" "F.Paste")
			(net "M_F_DQS_DP<0>")
		)
		(pad "154" smd rect
			(at 4.59994 7.649972 90)
			(size 1.8034 0.508)
			(layers "F.Cu" "F.Mask" "F.Paste")
			(net "GND")
		)
		(pad "155" smd rect
			(at 4.59994 8.50011 90)
			(size 1.8034 0.508)
			(layers "F.Cu" "F.Mask" "F.Paste")
			(net "M_F_DQ<6>")
		)
		(pad "156" smd rect
			(at 4.59994 9.349994 90)
			(size 1.8034 0.508)
			(layers "F.Cu" "F.Mask" "F.Paste")
			(net "GND")
		)
		(pad "157" smd rect
			(at 4.59994 10.199878 90)
			(size 1.8034 0.508)
			(layers "F.Cu" "F.Mask" "F.Paste")
			(net "M_F_DQ<2>")
		)
		(pad "158" smd rect
			(at 4.59994 11.050016 90)
			(size 1.8034 0.508)
			(layers "F.Cu" "F.Mask" "F.Paste")
			(net "GND")
		)
		(pad "159" smd rect
			(at 4.59994 11.8999 90)
			(size 1.8034 0.508)
			(layers "F.Cu" "F.Mask" "F.Paste")
			(net "M_F_DQ<12>")
		)
		(pad "160" smd rect
			(at 4.59994 12.750038 90)
			(size 1.8034 0.508)
			(layers "F.Cu" "F.Mask" "F.Paste")
			(net "GND")
		)
		(pad "161" smd rect
			(at 4.59994 13.599922 90)
			(size 1.8034 0.508)
			(layers "F.Cu" "F.Mask" "F.Paste")
			(net "M_F_DQ<8>")
		)
		(pad "162" smd rect
			(at 4.59994 14.45006 90)
			(size 1.8034 0.508)
			(layers "F.Cu" "F.Mask" "F.Paste")
			(net "GND")
		)
		(pad "163" smd rect
			(at 4.59994 15.299944 90)
			(size 1.8034 0.508)
			(layers "F.Cu" "F.Mask" "F.Paste")
			(net "M_F_DQS_DN<1>")
		)
		(pad "164" smd rect
			(at 4.59994 16.150082 90)
			(size 1.8034 0.508)
			(layers "F.Cu" "F.Mask" "F.Paste")
			(net "M_F_DQS_DP<1>")
		)
		(pad "165" smd rect
			(at 4.59994 16.999966 90)
			(size 1.8034 0.508)
			(layers "F.Cu" "F.Mask" "F.Paste")
			(net "GND")
		)
		(pad "166" smd rect
			(at 4.59994 17.850104 90)
			(size 1.8034 0.508)
			(layers "F.Cu" "F.Mask" "F.Paste")
			(net "M_F_DQ<14>")
		)
		(pad "167" smd rect
			(at 4.59994 18.699988 90)
			(size 1.8034 0.508)
			(layers "F.Cu" "F.Mask" "F.Paste")
			(net "GND")
		)
		(pad "168" smd rect
			(at 4.59994 19.550126 90)
			(size 1.8034 0.508)
			(layers "F.Cu" "F.Mask" "F.Paste")
			(net "M_F_DQ<10>")
		)
		(pad "169" smd rect
			(at 4.59994 20.40001 90)
			(size 1.8034 0.508)
			(layers "F.Cu" "F.Mask" "F.Paste")
			(net "GND")
		)
		(pad "170" smd rect
			(at 4.59994 21.249894 90)
			(size 1.8034 0.508)
			(layers "F.Cu" "F.Mask" "F.Paste")
			(net "M_F_DQ<20>")
		)
		(pad "171" smd rect
			(at 4.59994 22.100032 90)
			(size 1.8034 0.508)
			(layers "F.Cu" "F.Mask" "F.Paste")
			(net "GND")
		)
		(pad "172" smd rect
			(at 4.59994 22.949916 90)
			(size 1.8034 0.508)
			(layers "F.Cu" "F.Mask" "F.Paste")
			(net "M_F_DQ<16>")
		)
		(pad "173" smd rect
			(at 4.59994 23.800054 90)
			(size 1.8034 0.508)
			(layers "F.Cu" "F.Mask" "F.Paste")
			(net "GND")
		)
		(pad "174" smd rect
			(at 4.59994 24.649938 90)
			(size 1.8034 0.508)
			(layers "F.Cu" "F.Mask" "F.Paste")
			(net "M_F_DQS_DN<2>")
		)
		(pad "175" smd rect
			(at 4.59994 25.500076 90)
			(size 1.8034 0.508)
			(layers "F.Cu" "F.Mask" "F.Paste")
			(net "M_F_DQS_DP<2>")
		)
		(pad "176" smd rect
			(at 4.59994 26.34996 90)
			(size 1.8034 0.508)
			(layers "F.Cu" "F.Mask" "F.Paste")
			(net "GND")
		)
		(pad "177" smd rect
			(at 4.59994 27.200098 90)
			(size 1.8034 0.508)
			(layers "F.Cu" "F.Mask" "F.Paste")
			(net "M_F_DQ<22>")
		)
		(pad "178" smd rect
			(at 4.59994 28.049982 90)
			(size 1.8034 0.508)
			(layers "F.Cu" "F.Mask" "F.Paste")
			(net "GND")
		)
		(pad "179" smd rect
			(at 4.59994 28.90012 90)
			(size 1.8034 0.508)
			(layers "F.Cu" "F.Mask" "F.Paste")
			(net "M_F_DQ<18>")
		)
		(pad "180" smd rect
			(at 4.59994 29.750004 90)
			(size 1.8034 0.508)
			(layers "F.Cu" "F.Mask" "F.Paste")
			(net "GND")
		)
		(pad "181" smd rect
			(at 4.59994 30.599888 90)
			(size 1.8034 0.508)
			(layers "F.Cu" "F.Mask" "F.Paste")
			(net "M_F_DQ<28>")
		)
		(pad "182" smd rect
			(at 4.59994 31.450026 90)
			(size 1.8034 0.508)
			(layers "F.Cu" "F.Mask" "F.Paste")
			(net "GND")
		)
		(pad "183" smd rect
			(at 4.59994 32.29991 90)
			(size 1.8034 0.508)
			(layers "F.Cu" "F.Mask" "F.Paste")
			(net "M_F_DQ<24>")
		)
		(pad "184" smd rect
			(at 4.59994 33.150048 90)
			(size 1.8034 0.508)
			(layers "F.Cu" "F.Mask" "F.Paste")
			(net "GND")
		)
		(pad "185" smd rect
			(at 4.59994 33.999932 90)
			(size 1.8034 0.508)
			(layers "F.Cu" "F.Mask" "F.Paste")
			(net "M_F_DQS_DN<3>")
		)
		(pad "186" smd rect
			(at 4.59994 34.85007 90)
			(size 1.8034 0.508)
			(layers "F.Cu" "F.Mask" "F.Paste")
			(net "M_F_DQS_DP<3>")
		)
		(pad "187" smd rect
			(at 4.59994 35.699954 90)
			(size 1.8034 0.508)
			(layers "F.Cu" "F.Mask" "F.Paste")
			(net "GND")
		)
		(pad "188" smd rect
			(at 4.59994 36.550092 90)
			(size 1.8034 0.508)
			(layers "F.Cu" "F.Mask" "F.Paste")
			(net "M_F_DQ<30>")
		)
		(pad "189" smd rect
			(at 4.59994 37.399976 90)
			(size 1.8034 0.508)
			(layers "F.Cu" "F.Mask" "F.Paste")
			(net "GND")
		)
		(pad "190" smd rect
			(at 4.59994 38.250114 90)
			(size 1.8034 0.508)
			(layers "F.Cu" "F.Mask" "F.Paste")
			(net "M_F_DQ<26>")
		)
		(pad "191" smd rect
			(at 4.59994 39.099998 90)
			(size 1.8034 0.508)
			(layers "F.Cu" "F.Mask" "F.Paste")
			(net "GND")
		)
		(pad "192" smd rect
			(at 4.59994 39.949882 90)
			(size 1.8034 0.508)
			(layers "F.Cu" "F.Mask" "F.Paste")
			(net "M_F_ECC<4>")
		)
		(pad "193" smd rect
			(at 4.59994 40.80002 90)
			(size 1.8034 0.508)
			(layers "F.Cu" "F.Mask" "F.Paste")
			(net "GND")
		)
		(pad "194" smd rect
			(at 4.59994 41.649904 90)
			(size 1.8034 0.508)
			(layers "F.Cu" "F.Mask" "F.Paste")
			(net "M_F_ECC<0>")
		)
		(pad "195" smd rect
			(at 4.59994 42.500042 90)
			(size 1.8034 0.508)
			(layers "F.Cu" "F.Mask" "F.Paste")
			(net "GND")
		)
		(pad "196" smd rect
			(at 4.59994 43.349926 90)
			(size 1.8034 0.508)
			(layers "F.Cu" "F.Mask" "F.Paste")
			(net "M_F_DQS_DN<8>")
		)
		(pad "197" smd rect
			(at 4.59994 44.200064 90)
			(size 1.8034 0.508)
			(layers "F.Cu" "F.Mask" "F.Paste")
			(net "M_F_DQS_DP<8>")
		)
		(pad "198" smd rect
			(at 4.59994 45.049948 90)
			(size 1.8034 0.508)
			(layers "F.Cu" "F.Mask" "F.Paste")
			(net "GND")
		)
		(pad "199" smd rect
			(at 4.59994 45.900086 90)
			(size 1.8034 0.508)
			(layers "F.Cu" "F.Mask" "F.Paste")
			(net "M_F_ECC<6>")
		)
		(pad "200" smd rect
			(at 4.59994 46.74997 90)
			(size 1.8034 0.508)
			(layers "F.Cu" "F.Mask" "F.Paste")
			(net "GND")
		)
		(pad "201" smd rect
			(at 4.59994 47.600108 90)
			(size 1.8034 0.508)
			(layers "F.Cu" "F.Mask" "F.Paste")
			(net "M_F_ECC<2>")
		)
		(pad "202" smd rect
			(at 4.59994 48.449992 90)
			(size 1.8034 0.508)
			(layers "F.Cu" "F.Mask" "F.Paste")
			(net "GND")
		)
		(pad "203" smd rect
			(at 4.59994 49.299876 90)
			(size 1.8034 0.508)
			(layers "F.Cu" "F.Mask" "F.Paste")
			(net "M_F_CKE<1>")
		)
		(pad "204" smd rect
			(at 4.59994 50.150014 90)
			(size 1.8034 0.508)
			(layers "F.Cu" "F.Mask" "F.Paste")
			(net "PVDDQ_DEF")
		)
		(pad "205" smd rect
			(at 4.59994 50.999898 90)
			(size 1.8034 0.508)
			(layers "F.Cu" "F.Mask" "F.Paste")
			(net "TP_CH_F_DIMM_F0_RFU_0")
		)
		(pad "206" smd rect
			(at 4.59994 51.850036 90)
			(size 1.8034 0.508)
			(layers "F.Cu" "F.Mask" "F.Paste")
			(net "PVDDQ_DEF")
		)
		(pad "207" smd rect
			(at 4.59994 52.69992 90)
			(size 1.8034 0.508)
			(layers "F.Cu" "F.Mask" "F.Paste")
			(net "M_F_BG<1>")
		)
		(pad "208" smd rect
			(at 4.59994 53.550058 90)
			(size 1.8034 0.508)
			(layers "F.Cu" "F.Mask" "F.Paste")
			(net "M_F_ALERT_N")
		)
		(pad "209" smd rect
			(at 4.59994 54.399942 90)
			(size 1.8034 0.508)
			(layers "F.Cu" "F.Mask" "F.Paste")
			(net "PVDDQ_DEF")
		)
		(pad "210" smd rect
			(at 4.59994 55.25008 90)
			(size 1.8034 0.508)
			(layers "F.Cu" "F.Mask" "F.Paste")
			(net "M_F_MA<11>")
		)
		(pad "211" smd rect
			(at 4.59994 56.099964 90)
			(size 1.8034 0.508)
			(layers "F.Cu" "F.Mask" "F.Paste")
			(net "M_F_MA<7>")
		)
		(pad "212" smd rect
			(at 4.59994 56.950102 90)
			(size 1.8034 0.508)
			(layers "F.Cu" "F.Mask" "F.Paste")
			(net "PVDDQ_DEF")
		)
		(pad "213" smd rect
			(at 4.59994 57.799986 90)
			(size 1.8034 0.508)
			(layers "F.Cu" "F.Mask" "F.Paste")
			(net "M_F_MA<5>")
		)
		(pad "214" smd rect
			(at 4.59994 58.650124 90)
			(size 1.8034 0.508)
			(layers "F.Cu" "F.Mask" "F.Paste")
			(net "M_F_MA<4>")
		)
		(pad "215" smd rect
			(at 4.59994 59.500008 90)
			(size 1.8034 0.508)
			(layers "F.Cu" "F.Mask" "F.Paste")
			(net "PVDDQ_DEF")
		)
		(pad "216" smd rect
			(at 4.59994 60.349892 90)
			(size 1.8034 0.508)
			(layers "F.Cu" "F.Mask" "F.Paste")
			(net "M_F_MA<2>")
		)
		(pad "217" smd rect
			(at 4.59994 61.20003 90)
			(size 1.8034 0.508)
			(layers "F.Cu" "F.Mask" "F.Paste")
			(net "PVDDQ_DEF")
		)
		(pad "218" smd rect
			(at 4.59994 62.049914 90)
			(size 1.8034 0.508)
			(layers "F.Cu" "F.Mask" "F.Paste")
			(net "M_F_CLK_DP<1>")
		)
		(pad "219" smd rect
			(at 4.59994 62.900052 90)
			(size 1.8034 0.508)
			(layers "F.Cu" "F.Mask" "F.Paste")
			(net "M_F_CLK_DN<1>")
		)
		(pad "220" smd rect
			(at 4.59994 63.749936 90)
			(size 1.8034 0.508)
			(layers "F.Cu" "F.Mask" "F.Paste")
			(net "PVDDQ_DEF")
		)
		(pad "221" smd rect
			(at 4.59994 64.600074 90)
			(size 1.8034 0.508)
			(layers "F.Cu" "F.Mask" "F.Paste")
			(net "PVTT_DEF")
		)
		(pad "222" smd rect
			(at 4.59994 70.550024 90)
			(size 1.8034 0.508)
			(layers "F.Cu" "F.Mask" "F.Paste")
			(net "M_F_PAR")
		)
		(pad "223" smd rect
			(at 4.59994 71.399908 90)
			(size 1.8034 0.508)
			(layers "F.Cu" "F.Mask" "F.Paste")
			(net "PVDDQ_DEF")
		)
		(pad "224" smd rect
			(at 4.59994 72.250046 90)
			(size 1.8034 0.508)
			(layers "F.Cu" "F.Mask" "F.Paste")
			(net "M_F_BA<1>")
		)
		(pad "225" smd rect
			(at 4.59994 73.09993 90)
			(size 1.8034 0.508)
			(layers "F.Cu" "F.Mask" "F.Paste")
			(net "M_F_MA<10>")
		)
		(pad "226" smd rect
			(at 4.59994 73.950068 90)
			(size 1.8034 0.508)
			(layers "F.Cu" "F.Mask" "F.Paste")
			(net "PVDDQ_DEF")
		)
		(pad "227" smd rect
			(at 4.59994 74.799952 90)
			(size 1.8034 0.508)
			(layers "F.Cu" "F.Mask" "F.Paste")
			(net "TP_CH_F_DIMM_F0_RFU_1")
		)
		(pad "228" smd rect
			(at 4.59994 75.65009 90)
			(size 1.8034 0.508)
			(layers "F.Cu" "F.Mask" "F.Paste")
			(net "M_F_MA<14>")
		)
		(pad "229" smd rect
			(at 4.59994 76.499974 90)
			(size 1.8034 0.508)
			(layers "F.Cu" "F.Mask" "F.Paste")
			(net "PVDDQ_DEF")
		)
		(pad "230" smd rect
			(at 4.59994 77.350112 90)
			(size 1.8034 0.508)
			(layers "F.Cu" "F.Mask" "F.Paste")
			(net "FM_ADR_COMPLETE_DEF_N")
		)
		(pad "231" smd rect
			(at 4.59994 78.199996 90)
			(size 1.8034 0.508)
			(layers "F.Cu" "F.Mask" "F.Paste")
			(net "PVDDQ_DEF")
		)
		(pad "232" smd rect
			(at 4.59994 79.04988 90)
			(size 1.8034 0.508)
			(layers "F.Cu" "F.Mask" "F.Paste")
			(net "M_F_MA<13>")
		)
		(pad "233" smd rect
			(at 4.59994 79.900018 90)
			(size 1.8034 0.508)
			(layers "F.Cu" "F.Mask" "F.Paste")
			(net "PVDDQ_DEF")
		)
		(pad "234" smd rect
			(at 4.59994 80.749902 90)
			(size 1.8034 0.508)
			(layers "F.Cu" "F.Mask" "F.Paste")
			(net "M_F_MA<17>")
		)
		(pad "235" smd rect
			(at 4.59994 81.60004 90)
			(size 1.8034 0.508)
			(layers "F.Cu" "F.Mask" "F.Paste")
			(net "M_F_C<2>")
		)
		(pad "236" smd rect
			(at 4.59994 82.449924 90)
			(size 1.8034 0.508)
			(layers "F.Cu" "F.Mask" "F.Paste")
			(net "PVDDQ_DEF")
		)
		(pad "237" smd rect
			(at 4.59994 83.300062 90)
			(size 1.8034 0.508)
			(layers "F.Cu" "F.Mask" "F.Paste")
			(net "M_F_CS_N<3>")
		)
		(pad "238" smd rect
			(at 4.59994 84.149946 90)
			(size 1.8034 0.508)
			(layers "F.Cu" "F.Mask" "F.Paste")
			(net "PVPP_DEF")
		)
		(pad "239" smd rect
			(at 4.59994 85.000084 90)
			(size 1.8034 0.508)
			(layers "F.Cu" "F.Mask" "F.Paste")
			(net "GND")
		)
		(pad "240" smd rect
			(at 4.59994 85.849968 90)
			(size 1.8034 0.508)
			(layers "F.Cu" "F.Mask" "F.Paste")
			(net "M_F_DQ<36>")
		)
	)
)
